#ISCELL
  logical_power design_note *
  *
#ISCELL
  pure_quanta quanta_title_block_c *
  *
#ISCELL
  standard tap *
  page33_i1
#ISCELL
  standard tap *
  page33_i10
#ISCELL
  standard offpage *
  page33_i101
#CELL
  pure_quanta socket4677_azif0045p001c01cs *
  page33_i102
#ISCELL
  standard tap *
  page33_i103
#ISCELL
  standard tap *
  page33_i104
#ISCELL
  standard tap *
  page33_i105
#ISCELL
  standard tap *
  page33_i106
#ISCELL
  standard tap *
  page33_i107
#ISCELL
  standard tap *
  page33_i108
#ISCELL
  standard tap *
  page33_i109
#ISCELL
  standard tap *
  page33_i11
#ISCELL
  standard tap *
  page33_i111
#ISCELL
  standard tap *
  page33_i112
#ISCELL
  standard tap *
  page33_i113
#ISCELL
  standard tap *
  page33_i114
#ISCELL
  standard tap *
  page33_i115
#ISCELL
  standard tap *
  page33_i116
#ISCELL
  standard tap *
  page33_i117
#ISCELL
  standard tap *
  page33_i118
#ISCELL
  standard tap *
  page33_i119
#ISCELL
  standard tap *
  page33_i12
#ISCELL
  standard tap *
  page33_i120
#ISCELL
  standard tap *
  page33_i121
#ISCELL
  standard tap *
  page33_i122
#ISCELL
  standard tap *
  page33_i123
#ISCELL
  standard tap *
  page33_i124
#ISCELL
  standard tap *
  page33_i125
#ISCELL
  standard tap *
  page33_i126
#ISCELL
  standard tap *
  page33_i127
#ISCELL
  standard tap *
  page33_i128
#ISCELL
  standard tap *
  page33_i129
#ISCELL
  standard tap *
  page33_i13
#ISCELL
  standard tap *
  page33_i130
#ISCELL
  standard tap *
  page33_i131
#ISCELL
  standard tap *
  page33_i132
#ISCELL
  standard tap *
  page33_i133
#ISCELL
  standard tap *
  page33_i134
#ISCELL
  standard tap *
  page33_i135
#ISCELL
  standard offpage *
  page33_i136
#ISCELL
  standard tap *
  page33_i137
#ISCELL
  standard tap *
  page33_i138
#ISCELL
  standard tap *
  page33_i139
#ISCELL
  standard tap *
  page33_i14
#ISCELL
  standard tap *
  page33_i140
#ISCELL
  standard tap *
  page33_i141
#ISCELL
  standard tap *
  page33_i142
#ISCELL
  standard tap *
  page33_i143
#ISCELL
  standard tap *
  page33_i144
#ISCELL
  standard tap *
  page33_i145
#ISCELL
  standard tap *
  page33_i15
#ISCELL
  standard tap *
  page33_i16
#ISCELL
  standard offpage *
  page33_i17
#ISCELL
  standard offpage *
  page33_i18
#ISCELL
  standard tap *
  page33_i19
#ISCELL
  standard tap *
  page33_i2
#ISCELL
  standard tap *
  page33_i20
#ISCELL
  standard tap *
  page33_i22
#ISCELL
  standard tap *
  page33_i24
#ISCELL
  standard tap *
  page33_i25
#ISCELL
  standard tap *
  page33_i27
#ISCELL
  standard tap *
  page33_i29
#ISCELL
  standard tap *
  page33_i30
#ISCELL
  standard tap *
  page33_i31
#ISCELL
  standard tap *
  page33_i32
#ISCELL
  standard tap *
  page33_i33
#ISCELL
  standard tap *
  page33_i34
#ISCELL
  standard tap *
  page33_i35
#ISCELL
  standard tap *
  page33_i36
#ISCELL
  standard tap *
  page33_i37
#ISCELL
  standard tap *
  page33_i38
#ISCELL
  standard tap *
  page33_i4
#ISCELL
  standard tap *
  page33_i40
#ISCELL
  standard tap *
  page33_i41
#ISCELL
  standard tap *
  page33_i42
#ISCELL
  standard tap *
  page33_i43
#ISCELL
  standard tap *
  page33_i44
#ISCELL
  standard tap *
  page33_i48
#ISCELL
  standard tap *
  page33_i5
#ISCELL
  standard tap *
  page33_i52
#ISCELL
  standard tap *
  page33_i53
#ISCELL
  standard tap *
  page33_i54
#ISCELL
  standard tap *
  page33_i56
#ISCELL
  standard tap *
  page33_i58
#ISCELL
  standard tap *
  page33_i59
#ISCELL
  standard tap *
  page33_i6
#ISCELL
  standard tap *
  page33_i61
#ISCELL
  standard tap *
  page33_i62
#ISCELL
  standard tap *
  page33_i7
#ISCELL
  standard tap *
  page33_i75
#ISCELL
  standard tap *
  page33_i76
#ISCELL
  standard tap *
  page33_i77
#ISCELL
  standard tap *
  page33_i78
#ISCELL
  standard tap *
  page33_i8
#ISCELL
  standard tap *
  page33_i81
#ISCELL
  standard tap *
  page33_i82
#ISCELL
  standard tap *
  page33_i84
#ISCELL
  standard tap *
  page33_i85
#ISCELL
  standard tap *
  page33_i86
#ISCELL
  standard tap *
  page33_i9
#ISCELL
  standard tap *
  page33_i99
